# BASEBOARD_FAB2 (Tioga Pass) — schematic netlist excerpt (pin names and nets, part order shuffled) for the footprints in the layout excerpt that follows; sources: Cadence DE-HDL packaged netlist, KiCad conversion of Wiwynn_Tioga_Pass_MB.brd

R25W99  RES  4.75K 1% EMPTY  pkg 0402  page 150 : A = P3V3_STBY ; B = BMC_STRAP_BIT5
R9W19  RES  240 1.0% CHIP  pkg 0402  page 248 : A = PVCCIO_CPU0 ; B = SMB_CPU0_PE_HP_GTL_R_SCL
C4D49  CAP_A  0.1UF 16V 10% X7R  pkg 0402V  page 202 : A = VR_FET_SW_P12V_STBY_PVCCIN_CPU0 ; B = GND

(kicad_pcb
	(version 20260206)
	(generator "pcbnew")
	(generator_version "10.0")
	(general
		(thickness 1.6)
		(legacy_teardrops no)
	)
	(paper "A4")
	(title_block
		(title "Wiwynn_Tioga_Pass_MB.brd")
		(comment 1 "Tioga Pass / footprints 1661-1663 of 4770")
	)
	(layers
		(0 "F.Cu" signal "TOP")
		(4 "In1.Cu" signal "L2GND")
		(6 "In2.Cu" signal "L3")
		(8 "In3.Cu" signal "L4GND")
		(10 "In4.Cu" signal "L5")
		(12 "In5.Cu" signal "L6GND")
		(14 "In6.Cu" signal "L7VCC")
		(16 "In7.Cu" signal "L8VCC")
		(18 "In8.Cu" signal "L9GND")
		(20 "In9.Cu" signal "L10")
		(22 "In10.Cu" signal "L11GND")
		(24 "In11.Cu" signal "L12")
		(26 "In12.Cu" signal "L13GND")
		(2 "B.Cu" signal "BOTTOM")
		(9 "F.Adhes" user "F.Adhesive")
		(11 "B.Adhes" user "B.Adhesive")
		(13 "F.Paste" user "Package Geometry/Pastemask Top")
		(15 "B.Paste" user "Package Geometry/Pastemask Bottom")
		(5 "F.SilkS" user "Ref Des/Silkscreen Top")
		(7 "B.SilkS" user "Ref Des/Silkscreen Bottom")
		(1 "F.Mask" user "Board Geometry/Soldermask Top")
		(3 "B.Mask" user "Board Geometry/Soldermask Bottom")
		(17 "Dwgs.User" user "User.Drawings")
		(19 "Cmts.User" user "User.Comments")
		(21 "Eco1.User" user "User.Eco1")
		(23 "Eco2.User" user "User.Eco2")
		(25 "Edge.Cuts" user "Board Geometry/Outline")
		(27 "Margin" user)
		(31 "F.CrtYd" user "Package Geometry/Place Bound Top")
		(29 "B.CrtYd" user "Package Geometry/Place Bound Bottom")
		(35 "F.Fab" user "Ref Des/Assembly Top")
		(33 "B.Fab" user "Ref Des/Assembly Bottom")
	)
	(footprint ""
		(layer "F.Cu")
		(at 419.6207 -105.029 90)
		(property "Reference" "R9W19"
			(at -0.8382 -0.67818 90)
			(unlocked yes)
			(layer "F.SilkS")
			(effects
				(font
					(size 0.4064 0.254)
					(thickness 0.1524)
				)
				(justify left)
			)
		)
		(property "Value" ""
			(at 0 0 90)
			(layer "F.Fab")
			(effects
				(font
					(size 1.27 1.27)
				)
			)
		)
		(duplicate_pad_numbers_are_jumpers no)
		(fp_poly
			(pts
				(xy -0.2794 -0.1016) (xy 0.2794 -0.1016) (xy 0.2794 0.9906) (xy -0.2794 0.9906)
			)
			(stroke
				(width 0)
				(type default)
			)
			(fill no)
			(layer "F.CrtYd")
		)
		(fp_line
			(start 0.2794 -0.1016)
			(end -0.2794 -0.1016)
			(stroke
				(width 0.1)
				(type default)
			)
			(layer "F.Fab")
		)
		(fp_line
			(start -0.2794 -0.1016)
			(end -0.2794 0.9906)
			(stroke
				(width 0.1)
				(type default)
			)
			(layer "F.Fab")
		)
		(fp_line
			(start 0.2794 0.9906)
			(end 0.2794 -0.1016)
			(stroke
				(width 0.1)
				(type default)
			)
			(layer "F.Fab")
		)
		(fp_line
			(start -0.2794 0.9906)
			(end 0.2794 0.9906)
			(stroke
				(width 0.1)
				(type default)
			)
			(layer "F.Fab")
		)
		(pad "1" smd rect
			(at 0 0 90)
			(size 0.508 0.508)
			(layers "F.Cu" "F.Mask" "F.Paste")
			(net "PVCCIO_CPU0")
		)
		(pad "2" smd rect
			(at 0 0.889 90)
			(size 0.508 0.508)
			(layers "F.Cu" "F.Mask" "F.Paste")
			(net "SMB_CPU0_PE_HP_GTL_R_SCL")
		)
		(zone
			(layer "F.Cu")
			(hatch none 0.5)
			(connect_pads
				(clearance 0)
			)
			(min_thickness 0.25)
			(keepout
				(tracks allowed)
				(vias not_allowed)
				(pads allowed)
				(copperpour not_allowed)
				(footprints allowed)
			)
			(placement
				(enabled no)
				(sheetname "")
			)
			(fill
				(thermal_gap 0.5)
				(thermal_bridge_width 0.5)
				(island_removal_mode 0)
			)
			(polygon
				(pts
					(xy 419.8747 -104.775) (xy 419.8747 -105.283) (xy 420.2557 -105.283) (xy 420.2557 -104.775)
				)
			)
		)
		(zone
			(layer "F.Cu")
			(hatch none 0.5)
			(connect_pads
				(clearance 0)
			)
			(min_thickness 0.25)
			(keepout
				(tracks not_allowed)
				(vias allowed)
				(pads allowed)
				(copperpour not_allowed)
				(footprints allowed)
			)
			(placement
				(enabled no)
				(sheetname "")
			)
			(fill
				(thermal_gap 0.5)
				(thermal_bridge_width 0.5)
				(island_removal_mode 0)
			)
			(polygon
				(pts
					(xy 420.2557 -104.775) (xy 420.2557 -105.283) (xy 419.8747 -105.283) (xy 419.8747 -104.775)
				)
			)
		)
	)
	(footprint ""
		(layer "F.Cu")
		(at 420.865046 -48.968152)
		(property "Reference" "R25W99"
			(at -0.8382 -0.67818 0)
			(unlocked yes)
			(layer "F.SilkS")
			(effects
				(font
					(size 0.4064 0.254)
					(thickness 0.1524)
				)
				(justify left)
			)
		)
		(property "Value" ""
			(at 0 0 0)
			(layer "F.Fab")
			(effects
				(font
					(size 1.27 1.27)
				)
			)
		)
		(duplicate_pad_numbers_are_jumpers no)
		(fp_poly
			(pts
				(xy -0.2794 -0.1016) (xy 0.2794 -0.1016) (xy 0.2794 0.9906) (xy -0.2794 0.9906)
			)
			(stroke
				(width 0)
				(type default)
			)
			(fill no)
			(layer "F.CrtYd")
		)
		(fp_line
			(start -0.2794 -0.1016)
			(end -0.2794 0.9906)
			(stroke
				(width 0.1)
				(type default)
			)
			(layer "F.Fab")
		)
		(fp_line
			(start -0.2794 0.9906)
			(end 0.2794 0.9906)
			(stroke
				(width 0.1)
				(type default)
			)
			(layer "F.Fab")
		)
		(fp_line
			(start 0.2794 -0.1016)
			(end -0.2794 -0.1016)
			(stroke
				(width 0.1)
				(type default)
			)
			(layer "F.Fab")
		)
		(fp_line
			(start 0.2794 0.9906)
			(end 0.2794 -0.1016)
			(stroke
				(width 0.1)
				(type default)
			)
			(layer "F.Fab")
		)
		(pad "1" smd rect
			(at 0 0)
			(size 0.508 0.508)
			(layers "F.Cu" "F.Mask" "F.Paste")
			(net "P3V3_STBY")
		)
		(pad "2" smd rect
			(at 0 0.889)
			(size 0.508 0.508)
			(layers "F.Cu" "F.Mask" "F.Paste")
			(net "BMC_STRAP_BIT5")
		)
		(zone
			(layer "F.Cu")
			(hatch none 0.5)
			(connect_pads
				(clearance 0)
			)
			(min_thickness 0.25)
			(keepout
				(tracks allowed)
				(vias not_allowed)
				(pads allowed)
				(copperpour not_allowed)
				(footprints allowed)
			)
			(placement
				(enabled no)
				(sheetname "")
			)
			(fill
				(thermal_gap 0.5)
				(thermal_bridge_width 0.5)
				(island_removal_mode 0)
			)
			(polygon
				(pts
					(xy 420.611046 -48.714152) (xy 421.119046 -48.714152) (xy 421.119046 -48.333152) (xy 420.611046 -48.333152)
				)
			)
		)
		(zone
			(layer "F.Cu")
			(hatch none 0.5)
			(connect_pads
				(clearance 0)
			)
			(min_thickness 0.25)
			(keepout
				(tracks not_allowed)
				(vias allowed)
				(pads allowed)
				(copperpour not_allowed)
				(footprints allowed)
			)
			(placement
				(enabled no)
				(sheetname "")
			)
			(fill
				(thermal_gap 0.5)
				(thermal_bridge_width 0.5)
				(island_removal_mode 0)
			)
			(polygon
				(pts
					(xy 420.611046 -48.333152) (xy 421.119046 -48.333152) (xy 421.119046 -48.714152) (xy 420.611046 -48.714152)
				)
			)
		)
	)
	(footprint ""
		(layer "F.Cu")
		(at 198.02221 -68.49237 90)
		(property "Reference" "C4D49"
			(at -0.8382 -0.67818 90)
			(unlocked yes)
			(layer "F.SilkS")
			(effects
				(font
					(size 0.4064 0.254)
					(thickness 0.1524)
				)
				(justify left)
			)
		)
		(property "Value" ""
			(at 0 0 90)
			(layer "F.Fab")
			(effects
				(font
					(size 1.27 1.27)
				)
			)
		)
		(duplicate_pad_numbers_are_jumpers no)
		(fp_poly
			(pts
				(xy 0.3048 -0.1016) (xy 0.3048 0.9906) (xy -0.3048 0.9906) (xy -0.3048 -0.1016)
			)
			(stroke
				(width 0)
				(type default)
			)
			(fill no)
			(layer "F.CrtYd")
		)
		(fp_line
			(start 0.3048 -0.1016)
			(end -0.3048 -0.1016)
			(stroke
				(width 0.1)
				(type default)
			)
			(layer "F.Fab")
		)
		(fp_line
			(start -0.3048 -0.1016)
			(end -0.3048 0.9906)
			(stroke
				(width 0.1)
				(type default)
			)
			(layer "F.Fab")
		)
		(fp_line
			(start 0.3048 0.9906)
			(end 0.3048 -0.1016)
			(stroke
				(width 0.1)
				(type default)
			)
			(layer "F.Fab")
		)
		(fp_line
			(start -0.3048 0.9906)
			(end 0.3048 0.9906)
			(stroke
				(width 0.1)
				(type default)
			)
			(layer "F.Fab")
		)
		(pad "1" smd rect
			(at 0 0 90)
			(size 0.508 0.508)
			(layers "F.Cu" "F.Mask" "F.Paste")
			(net "VR_FET_SW_P12V_STBY_PVCCIN_CPU0")
		)
		(pad "2" smd rect
			(at 0 0.889 90)
			(size 0.508 0.508)
			(layers "F.Cu" "F.Mask" "F.Paste")
			(net "GND")
		)
		(zone
			(layer "F.Cu")
			(hatch none 0.5)
			(connect_pads
				(clearance 0)
			)
			(min_thickness 0.25)
			(keepout
				(tracks allowed)
				(vias not_allowed)
				(pads allowed)
				(copperpour not_allowed)
				(footprints allowed)
			)
			(placement
				(enabled no)
				(sheetname "")
			)
			(fill
				(thermal_gap 0.5)
				(thermal_bridge_width 0.5)
				(island_removal_mode 0)
			)
			(polygon
				(pts
					(xy 198.27621 -68.23837) (xy 198.27621 -68.74637) (xy 198.65721 -68.74637) (xy 198.65721 -68.23837)
				)
			)
		)
		(zone
			(layer "F.Cu")
			(hatch none 0.5)
			(connect_pads
				(clearance 0)
			)
			(min_thickness 0.25)
			(keepout
				(tracks not_allowed)
				(vias allowed)
				(pads allowed)
				(copperpour not_allowed)
				(footprints allowed)
			)
			(placement
				(enabled no)
				(sheetname "")
			)
			(fill
				(thermal_gap 0.5)
				(thermal_bridge_width 0.5)
				(island_removal_mode 0)
			)
			(polygon
				(pts
					(xy 198.65721 -68.23837) (xy 198.65721 -68.74637) (xy 198.27621 -68.74637) (xy 198.27621 -68.23837)
				)
			)
		)
	)
)
